(kicad_pcb
	(version 20260206)
	(generator "pcbnew")
	(generator_version "10.0")
	(general
		(thickness 1.6)
		(legacy_teardrops no)
	)
	(paper "A4")
	(title_block
		(title "Wiwynn_Tioga_Pass_MB.brd")
		(comment 1 "Tioga Pass / footprints 3239-3246 of 4770")
	)
	(layers
		(0 "F.Cu" signal "TOP")
		(4 "In1.Cu" signal "L2GND")
		(6 "In2.Cu" signal "L3")
		(8 "In3.Cu" signal "L4GND")
		(10 "In4.Cu" signal "L5")
		(12 "In5.Cu" signal "L6GND")
		(14 "In6.Cu" signal "L7VCC")
		(16 "In7.Cu" signal "L8VCC")
		(18 "In8.Cu" signal "L9GND")
		(20 "In9.Cu" signal "L10")
		(22 "In10.Cu" signal "L11GND")
		(24 "In11.Cu" signal "L12")
		(26 "In12.Cu" signal "L13GND")
		(2 "B.Cu" signal "BOTTOM")
		(9 "F.Adhes" user "F.Adhesive")
		(11 "B.Adhes" user "B.Adhesive")
		(13 "F.Paste" user "Package Geometry/Pastemask Top")
		(15 "B.Paste" user "Package Geometry/Pastemask Bottom")
		(5 "F.SilkS" user "Ref Des/Silkscreen Top")
		(7 "B.SilkS" user "Ref Des/Silkscreen Bottom")
		(1 "F.Mask" user "Board Geometry/Soldermask Top")
		(3 "B.Mask" user "Board Geometry/Soldermask Bottom")
		(17 "Dwgs.User" user "User.Drawings")
		(19 "Cmts.User" user "User.Comments")
		(21 "Eco1.User" user "User.Eco1")
		(23 "Eco2.User" user "User.Eco2")
		(25 "Edge.Cuts" user "Board Geometry/Outline")
		(27 "Margin" user)
		(31 "F.CrtYd" user "Package Geometry/Place Bound Top")
		(29 "B.CrtYd" user "Package Geometry/Place Bound Bottom")
		(35 "F.Fab" user "Ref Des/Assembly Top")
		(33 "B.Fab" user "Ref Des/Assembly Bottom")
	)
	(footprint ""
		(layer "B.Cu")
		(at 18.0594 -154.5844 -90)
		(property "Reference" "C9L2"
			(at -2.99593 5.1054 0)
			(unlocked yes)
			(layer "B.SilkS")
			(effects
				(font
					(size 0.7874 0.5842)
					(thickness 0.1524)
				)
				(justify mirror)
			)
		)
		(property "Value" ""
			(at 0 0 90)
			(layer "B.Fab")
			(effects
				(font
					(size 1.27 1.27)
				)
				(justify mirror)
			)
		)
		(duplicate_pad_numbers_are_jumpers no)
		(fp_line
			(start -2.286 7.366)
			(end -1.600708 7.366)
			(stroke
				(width 0.1524)
				(type default)
			)
			(layer "B.SilkS")
		)
		(fp_line
			(start -2.286 7.366)
			(end -2.286 1.63195)
			(stroke
				(width 0.1524)
				(type default)
			)
			(layer "B.SilkS")
		)
		(fp_line
			(start 2.286 7.366)
			(end 1.60147 7.366)
			(stroke
				(width 0.1524)
				(type default)
			)
			(layer "B.SilkS")
		)
		(fp_line
			(start 2.286 7.366)
			(end 2.286 1.632712)
			(stroke
				(width 0.1524)
				(type default)
			)
			(layer "B.SilkS")
		)
		(fp_line
			(start -2.504948 1.633728)
			(end -1.6002 1.633728)
			(stroke
				(width 0.1524)
				(type default)
			)
			(layer "B.SilkS")
		)
		(fp_line
			(start 2.563114 1.633728)
			(end 1.6002 1.633728)
			(stroke
				(width 0.1524)
				(type default)
			)
			(layer "B.SilkS")
		)
		(fp_line
			(start -2.504948 -1.616456)
			(end -2.504948 1.633728)
			(stroke
				(width 0.1524)
				(type default)
			)
			(layer "B.SilkS")
		)
		(fp_line
			(start -1.6002 -1.616456)
			(end -2.504948 -1.616456)
			(stroke
				(width 0.1524)
				(type default)
			)
			(layer "B.SilkS")
		)
		(fp_line
			(start 1.6002 -1.616456)
			(end 2.563114 -1.616456)
			(stroke
				(width 0.1524)
				(type default)
			)
			(layer "B.SilkS")
		)
		(fp_line
			(start 2.563114 -1.616456)
			(end 2.563114 1.633728)
			(stroke
				(width 0.1524)
				(type default)
			)
			(layer "B.SilkS")
		)
		(fp_rect
			(start 2.286 -0.254)
			(end -2.286 7.366)
			(stroke
				(width 0)
				(type default)
			)
			(fill no)
			(layer "B.CrtYd")
		)
		(fp_line
			(start -2.286 7.366)
			(end 2.286 7.366)
			(stroke
				(width 0.1)
				(type default)
			)
			(layer "B.Fab")
		)
		(fp_line
			(start 2.286 7.366)
			(end 2.286 -0.254)
			(stroke
				(width 0.1)
				(type default)
			)
			(layer "B.Fab")
		)
		(fp_line
			(start -2.286 -0.254)
			(end -2.286 7.366)
			(stroke
				(width 0.1)
				(type default)
			)
			(layer "B.Fab")
		)
		(fp_line
			(start 2.286 -0.254)
			(end -2.286 -0.254)
			(stroke
				(width 0.1)
				(type default)
			)
			(layer "B.Fab")
		)
		(pad "1" smd rect
			(at 0 0 90)
			(size 2.54 3.048)
			(layers "B.Cu" "B.Mask" "B.Paste")
			(net "PVDDQ_KLM")
		)
		(pad "2" smd rect
			(at 0 7.112 90)
			(size 2.54 3.048)
			(layers "B.Cu" "B.Mask" "B.Paste")
			(net "GND")
		)
	)
	(footprint ""
		(layer "B.Cu")
		(at 394.35405 -157.226 -90)
		(property "Reference" "C2L2"
			(at 0 0 90)
			(layer "B.SilkS")
			(hide yes)
			(effects
				(font
					(size 1.27 1.27)
				)
				(justify mirror)
			)
		)
		(property "Value" ""
			(at 0 0 90)
			(layer "B.Fab")
			(effects
				(font
					(size 1.27 1.27)
				)
				(justify mirror)
			)
		)
		(duplicate_pad_numbers_are_jumpers no)
		(fp_poly
			(pts
				(xy -0.3048 -0.1016) (xy -0.3048 0.9906) (xy 0.3048 0.9906) (xy 0.3048 -0.1016)
			)
			(stroke
				(width 0)
				(type default)
			)
			(fill no)
			(layer "B.CrtYd")
		)
		(fp_line
			(start -0.3048 0.9906)
			(end -0.3048 -0.1016)
			(stroke
				(width 0.1)
				(type default)
			)
			(layer "B.Fab")
		)
		(fp_line
			(start 0.3048 0.9906)
			(end -0.3048 0.9906)
			(stroke
				(width 0.1)
				(type default)
			)
			(layer "B.Fab")
		)
		(fp_line
			(start -0.3048 -0.1016)
			(end 0.3048 -0.1016)
			(stroke
				(width 0.1)
				(type default)
			)
			(layer "B.Fab")
		)
		(fp_line
			(start 0.3048 -0.1016)
			(end 0.3048 0.9906)
			(stroke
				(width 0.1)
				(type default)
			)
			(layer "B.Fab")
		)
		(pad "1" smd rect
			(at 0 0 90)
			(size 0.508 0.508)
			(layers "B.Cu" "B.Mask" "B.Paste")
			(net "VR_P1V05_PCH_STBY_AVSP")
		)
		(pad "2" smd rect
			(at 0 0.889 90)
			(size 0.508 0.508)
			(layers "B.Cu" "B.Mask" "B.Paste")
			(net "VSENSE_P1V05_PCH_STBY_AVSN")
		)
		(zone
			(layer "B.Cu")
			(hatch none 0.5)
			(connect_pads
				(clearance 0)
			)
			(min_thickness 0.25)
			(keepout
				(tracks not_allowed)
				(vias allowed)
				(pads allowed)
				(copperpour not_allowed)
				(footprints allowed)
			)
			(placement
				(enabled no)
				(sheetname "")
			)
			(fill
				(thermal_gap 0.5)
				(thermal_bridge_width 0.5)
				(island_removal_mode 0)
			)
			(polygon
				(pts
					(xy 393.71905 -156.972) (xy 393.71905 -157.48) (xy 394.10005 -157.48) (xy 394.10005 -156.972)
				)
			)
		)
		(zone
			(layer "B.Cu")
			(hatch none 0.5)
			(connect_pads
				(clearance 0)
			)
			(min_thickness 0.25)
			(keepout
				(tracks allowed)
				(vias not_allowed)
				(pads allowed)
				(copperpour not_allowed)
				(footprints allowed)
			)
			(placement
				(enabled no)
				(sheetname "")
			)
			(fill
				(thermal_gap 0.5)
				(thermal_bridge_width 0.5)
				(island_removal_mode 0)
			)
			(polygon
				(pts
					(xy 394.10005 -156.972) (xy 394.10005 -157.48) (xy 393.71905 -157.48) (xy 393.71905 -156.972)
				)
			)
		)
	)
	(footprint ""
		(layer "B.Cu")
		(at 423.672 -21.59 90)
		(property "Reference" "R25W58"
			(at 0 0 90)
			(layer "B.SilkS")
			(hide yes)
			(effects
				(font
					(size 1.27 1.27)
				)
				(justify mirror)
			)
		)
		(property "Value" "*"
			(at -0.064008 -4.108196 90)
			(unlocked yes)
			(layer "B.Fab")
			(hide yes)
			(effects
				(font
					(size 1.27 1.016)
					(thickness 0.1524)
				)
				(justify mirror)
			)
		)
		(property "Device Type" "18KR2F-GP_RCL_GP-18KR2F-GP,64.A"
			(at -0.064008 -5.632196 90)
			(unlocked yes)
			(layer "B.Fab")
			(hide yes)
			(effects
				(font
					(size 1.27 1.016)
					(thickness 0.1524)
				)
				(justify mirror)
			)
		)
		(duplicate_pad_numbers_are_jumpers no)
		(fp_line
			(start 0.508 -0.9398)
			(end 0.508 0.9398)
			(stroke
				(width 0.1524)
				(type default)
			)
			(layer "B.SilkS")
		)
		(fp_line
			(start -0.508 -0.9398)
			(end 0.508 -0.9398)
			(stroke
				(width 0.1524)
				(type default)
			)
			(layer "B.SilkS")
		)
		(fp_rect
			(start 0.508 0.9398)
			(end -0.508 -0.9398)
			(stroke
				(width 0)
				(type default)
			)
			(fill no)
			(layer "B.CrtYd")
		)
		(fp_rect
			(start 0.508 0.9398)
			(end -0.508 -0.9398)
			(stroke
				(width 0)
				(type default)
			)
			(fill no)
			(layer "B.Fab")
		)
		(pad "1" smd custom
			(at 0 -0.4445 270)
			(size 0.1397 0.1397)
			(layers "B.Cu" "B.Mask" "B.Paste")
			(net "A_DACRSET")
			(options
				(clearance outline)
				(anchor circle)
			)
			(primitives
				(gr_poly
					(pts
						(arc
							(start -0.1778 0.2794)
							(mid -0.249642 0.249642)
							(end -0.2794 0.1778)
						)
						(arc
							(start -0.2794 -0.1778)
							(mid -0.249642 -0.249642)
							(end -0.1778 -0.2794)
						)
						(arc
							(start 0.1778 -0.2794)
							(mid 0.249642 -0.249642)
							(end 0.2794 -0.1778)
						)
						(arc
							(start 0.2794 0.1778)
							(mid 0.249642 0.249642)
							(end 0.1778 0.2794)
						)
					)
					(width 0)
					(fill yes)
				)
			)
		)
		(pad "2" smd custom
			(at 0 0.4445 270)
			(size 0.1397 0.1397)
			(layers "B.Cu" "B.Mask" "B.Paste")
			(net "GND")
			(options
				(clearance outline)
				(anchor circle)
			)
			(primitives
				(gr_poly
					(pts
						(arc
							(start -0.1778 0.2794)
							(mid -0.249642 0.249642)
							(end -0.2794 0.1778)
						)
						(arc
							(start -0.2794 -0.1778)
							(mid -0.249642 -0.249642)
							(end -0.1778 -0.2794)
						)
						(arc
							(start 0.1778 -0.2794)
							(mid 0.249642 -0.249642)
							(end 0.2794 -0.1778)
						)
						(arc
							(start 0.2794 0.1778)
							(mid 0.249642 0.249642)
							(end 0.1778 0.2794)
						)
					)
					(width 0)
					(fill yes)
				)
			)
		)
	)
	(footprint ""
		(layer "B.Cu")
		(at 107.8611 -140.208 90)
		(property "Reference" "C5G108"
			(at -1.14681 0.76708 180)
			(unlocked yes)
			(layer "B.SilkS")
			(effects
				(font
					(size 0.7874 0.5842)
					(thickness 0.1524)
				)
				(justify mirror)
			)
		)
		(property "Value" ""
			(at 0 0 90)
			(layer "B.Fab")
			(effects
				(font
					(size 1.27 1.27)
				)
				(justify mirror)
			)
		)
		(duplicate_pad_numbers_are_jumpers no)
		(fp_rect
			(start -0.4953 -0.2032)
			(end 0.4953 1.6002)
			(stroke
				(width 0)
				(type default)
			)
			(fill no)
			(layer "B.CrtYd")
		)
		(fp_line
			(start 0.4953 -0.2032)
			(end -0.4953 -0.2032)
			(stroke
				(width 0.1)
				(type default)
			)
			(layer "B.Fab")
		)
		(fp_line
			(start -0.4953 -0.2032)
			(end -0.4953 1.6002)
			(stroke
				(width 0.1)
				(type default)
			)
			(layer "B.Fab")
		)
		(fp_line
			(start 0.4953 1.6002)
			(end 0.4953 -0.2032)
			(stroke
				(width 0.1)
				(type default)
			)
			(layer "B.Fab")
		)
		(fp_line
			(start -0.4953 1.6002)
			(end 0.4953 1.6002)
			(stroke
				(width 0.1)
				(type default)
			)
			(layer "B.Fab")
		)
		(pad "1" smd rect
			(at 0 0 270)
			(size 0.762 0.889)
			(layers "B.Cu" "B.Mask" "B.Paste")
			(net "PVDDQ_KLM")
		)
		(pad "2" smd rect
			(at 0 1.397 270)
			(size 0.762 0.889)
			(layers "B.Cu" "B.Mask" "B.Paste")
			(net "GND")
		)
		(zone
			(layer "B.Cu")
			(hatch none 0.5)
			(connect_pads
				(clearance 0)
			)
			(min_thickness 0.25)
			(keepout
				(tracks not_allowed)
				(vias allowed)
				(pads allowed)
				(copperpour not_allowed)
				(footprints allowed)
			)
			(placement
				(enabled no)
				(sheetname "")
			)
			(fill
				(thermal_gap 0.5)
				(thermal_bridge_width 0.5)
				(island_removal_mode 0)
			)
			(polygon
				(pts
					(xy 108.3056 -139.827) (xy 108.8136 -139.827) (xy 108.8136 -140.589) (xy 108.3056 -140.589)
				)
			)
		)
	)
	(footprint ""
		(layer "B.Cu")
		(at 484.0732 -48.5267)
		(property "Reference" "C1R14"
			(at 0 0 0)
			(layer "B.SilkS")
			(hide yes)
			(effects
				(font
					(size 1.27 1.27)
				)
				(justify mirror)
			)
		)
		(property "Value" ""
			(at 0 0 0)
			(layer "B.Fab")
			(effects
				(font
					(size 1.27 1.27)
				)
				(justify mirror)
			)
		)
		(duplicate_pad_numbers_are_jumpers no)
		(fp_poly
			(pts
				(xy -0.3048 -0.1016) (xy -0.3048 0.9906) (xy 0.3048 0.9906) (xy 0.3048 -0.1016)
			)
			(stroke
				(width 0)
				(type default)
			)
			(fill no)
			(layer "B.CrtYd")
		)
		(fp_line
			(start -0.3048 -0.1016)
			(end 0.3048 -0.1016)
			(stroke
				(width 0.1)
				(type default)
			)
			(layer "B.Fab")
		)
		(fp_line
			(start -0.3048 0.9906)
			(end -0.3048 -0.1016)
			(stroke
				(width 0.1)
				(type default)
			)
			(layer "B.Fab")
		)
		(fp_line
			(start 0.3048 -0.1016)
			(end 0.3048 0.9906)
			(stroke
				(width 0.1)
				(type default)
			)
			(layer "B.Fab")
		)
		(fp_line
			(start 0.3048 0.9906)
			(end -0.3048 0.9906)
			(stroke
				(width 0.1)
				(type default)
			)
			(layer "B.Fab")
		)
		(pad "1" smd rect
			(at 0 0 180)
			(size 0.508 0.508)
			(layers "B.Cu" "B.Mask" "B.Paste")
			(net "P3V3_STBY")
		)
		(pad "2" smd rect
			(at 0 0.889 180)
			(size 0.508 0.508)
			(layers "B.Cu" "B.Mask" "B.Paste")
			(net "GND")
		)
		(zone
			(layer "B.Cu")
			(hatch none 0.5)
			(connect_pads
				(clearance 0)
			)
			(min_thickness 0.25)
			(keepout
				(tracks allowed)
				(vias not_allowed)
				(pads allowed)
				(copperpour not_allowed)
				(footprints allowed)
			)
			(placement
				(enabled no)
				(sheetname "")
			)
			(fill
				(thermal_gap 0.5)
				(thermal_bridge_width 0.5)
				(island_removal_mode 0)
			)
			(polygon
				(pts
					(xy 484.3272 -48.2727) (xy 483.8192 -48.2727) (xy 483.8192 -47.8917) (xy 484.3272 -47.8917)
				)
			)
		)
		(zone
			(layer "B.Cu")
			(hatch none 0.5)
			(connect_pads
				(clearance 0)
			)
			(min_thickness 0.25)
			(keepout
				(tracks not_allowed)
				(vias allowed)
				(pads allowed)
				(copperpour not_allowed)
				(footprints allowed)
			)
			(placement
				(enabled no)
				(sheetname "")
			)
			(fill
				(thermal_gap 0.5)
				(thermal_bridge_width 0.5)
				(island_removal_mode 0)
			)
			(polygon
				(pts
					(xy 484.3272 -47.8917) (xy 483.8192 -47.8917) (xy 483.8192 -48.2727) (xy 484.3272 -48.2727)
				)
			)
		)
	)
	(footprint ""
		(layer "B.Cu")
		(at 18.161 -45.72)
		(property "Reference" "C9R14"
			(at 0 0 0)
			(layer "B.SilkS")
			(hide yes)
			(effects
				(font
					(size 1.27 1.27)
				)
				(justify mirror)
			)
		)
		(property "Value" ""
			(at 0 0 0)
			(layer "B.Fab")
			(effects
				(font
					(size 1.27 1.27)
				)
				(justify mirror)
			)
		)
		(duplicate_pad_numbers_are_jumpers no)
		(fp_poly
			(pts
				(xy -0.3048 -0.1016) (xy -0.3048 0.9906) (xy 0.3048 0.9906) (xy 0.3048 -0.1016)
			)
			(stroke
				(width 0)
				(type default)
			)
			(fill no)
			(layer "B.CrtYd")
		)
		(fp_line
			(start -0.3048 -0.1016)
			(end 0.3048 -0.1016)
			(stroke
				(width 0.1)
				(type default)
			)
			(layer "B.Fab")
		)
		(fp_line
			(start -0.3048 0.9906)
			(end -0.3048 -0.1016)
			(stroke
				(width 0.1)
				(type default)
			)
			(layer "B.Fab")
		)
		(fp_line
			(start 0.3048 -0.1016)
			(end 0.3048 0.9906)
			(stroke
				(width 0.1)
				(type default)
			)
			(layer "B.Fab")
		)
		(fp_line
			(start 0.3048 0.9906)
			(end -0.3048 0.9906)
			(stroke
				(width 0.1)
				(type default)
			)
			(layer "B.Fab")
		)
		(pad "1" smd rect
			(at 0 0 180)
			(size 0.508 0.508)
			(layers "B.Cu" "B.Mask" "B.Paste")
			(net "P3V3_STBY")
		)
		(pad "2" smd rect
			(at 0 0.889 180)
			(size 0.508 0.508)
			(layers "B.Cu" "B.Mask" "B.Paste")
			(net "GND")
		)
		(zone
			(layer "B.Cu")
			(hatch none 0.5)
			(connect_pads
				(clearance 0)
			)
			(min_thickness 0.25)
			(keepout
				(tracks allowed)
				(vias not_allowed)
				(pads allowed)
				(copperpour not_allowed)
				(footprints allowed)
			)
			(placement
				(enabled no)
				(sheetname "")
			)
			(fill
				(thermal_gap 0.5)
				(thermal_bridge_width 0.5)
				(island_removal_mode 0)
			)
			(polygon
				(pts
					(xy 18.415 -45.466) (xy 17.907 -45.466) (xy 17.907 -45.085) (xy 18.415 -45.085)
				)
			)
		)
		(zone
			(layer "B.Cu")
			(hatch none 0.5)
			(connect_pads
				(clearance 0)
			)
			(min_thickness 0.25)
			(keepout
				(tracks not_allowed)
				(vias allowed)
				(pads allowed)
				(copperpour not_allowed)
				(footprints allowed)
			)
			(placement
				(enabled no)
				(sheetname "")
			)
			(fill
				(thermal_gap 0.5)
				(thermal_bridge_width 0.5)
				(island_removal_mode 0)
			)
			(polygon
				(pts
					(xy 18.415 -45.085) (xy 17.907 -45.085) (xy 17.907 -45.466) (xy 18.415 -45.466)
				)
			)
		)
	)
	(footprint ""
		(layer "B.Cu")
		(at 269.559532 -140.208 90)
		(property "Reference" "C5G74"
			(at -1.14681 0.76708 180)
			(unlocked yes)
			(layer "B.SilkS")
			(effects
				(font
					(size 0.7874 0.5842)
					(thickness 0.1524)
				)
				(justify mirror)
			)
		)
		(property "Value" ""
			(at 0 0 90)
			(layer "B.Fab")
			(effects
				(font
					(size 1.27 1.27)
				)
				(justify mirror)
			)
		)
		(duplicate_pad_numbers_are_jumpers no)
		(fp_rect
			(start -0.4953 -0.2032)
			(end 0.4953 1.6002)
			(stroke
				(width 0)
				(type default)
			)
			(fill no)
			(layer "B.CrtYd")
		)
		(fp_line
			(start 0.4953 -0.2032)
			(end -0.4953 -0.2032)
			(stroke
				(width 0.1)
				(type default)
			)
			(layer "B.Fab")
		)
		(fp_line
			(start -0.4953 -0.2032)
			(end -0.4953 1.6002)
			(stroke
				(width 0.1)
				(type default)
			)
			(layer "B.Fab")
		)
		(fp_line
			(start 0.4953 1.6002)
			(end 0.4953 -0.2032)
			(stroke
				(width 0.1)
				(type default)
			)
			(layer "B.Fab")
		)
		(fp_line
			(start -0.4953 1.6002)
			(end 0.4953 1.6002)
			(stroke
				(width 0.1)
				(type default)
			)
			(layer "B.Fab")
		)
		(pad "1" smd rect
			(at 0 0 270)
			(size 0.762 0.889)
			(layers "B.Cu" "B.Mask" "B.Paste")
			(net "PVDDQ_DEF")
		)
		(pad "2" smd rect
			(at 0 1.397 270)
			(size 0.762 0.889)
			(layers "B.Cu" "B.Mask" "B.Paste")
			(net "GND")
		)
		(zone
			(layer "B.Cu")
			(hatch none 0.5)
			(connect_pads
				(clearance 0)
			)
			(min_thickness 0.25)
			(keepout
				(tracks not_allowed)
				(vias allowed)
				(pads allowed)
				(copperpour not_allowed)
				(footprints allowed)
			)
			(placement
				(enabled no)
				(sheetname "")
			)
			(fill
				(thermal_gap 0.5)
				(thermal_bridge_width 0.5)
				(island_removal_mode 0)
			)
			(polygon
				(pts
					(xy 270.004032 -139.827) (xy 270.512032 -139.827) (xy 270.512032 -140.589) (xy 270.004032 -140.589)
				)
			)
		)
	)
	(footprint ""
		(layer "B.Cu")
		(at 276.000464 -3.3528 90)
		(property "Reference" "C5G56"
			(at -1.14681 0.76708 180)
			(unlocked yes)
			(layer "B.SilkS")
			(effects
				(font
					(size 0.7874 0.5842)
					(thickness 0.1524)
				)
				(justify mirror)
			)
		)
		(property "Value" ""
			(at 0 0 90)
			(layer "B.Fab")
			(effects
				(font
					(size 1.27 1.27)
				)
				(justify mirror)
			)
		)
		(duplicate_pad_numbers_are_jumpers no)
		(fp_rect
			(start -0.4953 -0.2032)
			(end 0.4953 1.6002)
			(stroke
				(width 0)
				(type default)
			)
			(fill no)
			(layer "B.CrtYd")
		)
		(fp_line
			(start 0.4953 -0.2032)
			(end -0.4953 -0.2032)
			(stroke
				(width 0.1)
				(type default)
			)
			(layer "B.Fab")
		)
		(fp_line
			(start -0.4953 -0.2032)
			(end -0.4953 1.6002)
			(stroke
				(width 0.1)
				(type default)
			)
			(layer "B.Fab")
		)
		(fp_line
			(start 0.4953 1.6002)
			(end 0.4953 -0.2032)
			(stroke
				(width 0.1)
				(type default)
			)
			(layer "B.Fab")
		)
		(fp_line
			(start -0.4953 1.6002)
			(end 0.4953 1.6002)
			(stroke
				(width 0.1)
				(type default)
			)
			(layer "B.Fab")
		)
		(pad "1" smd rect
			(at 0 0 270)
			(size 0.762 0.889)
			(layers "B.Cu" "B.Mask" "B.Paste")
			(net "PVDDQ_ABC")
		)
		(pad "2" smd rect
			(at 0 1.397 270)
			(size 0.762 0.889)
			(layers "B.Cu" "B.Mask" "B.Paste")
			(net "GND")
		)
		(zone
			(layer "B.Cu")
			(hatch none 0.5)
			(connect_pads
				(clearance 0)
			)
			(min_thickness 0.25)
			(keepout
				(tracks not_allowed)
				(vias allowed)
				(pads allowed)
				(copperpour not_allowed)
				(footprints allowed)
			)
			(placement
				(enabled no)
				(sheetname "")
			)
			(fill
				(thermal_gap 0.5)
				(thermal_bridge_width 0.5)
				(island_removal_mode 0)
			)
			(polygon
				(pts
					(xy 276.444964 -2.9718) (xy 276.952964 -2.9718) (xy 276.952964 -3.7338) (xy 276.444964 -3.7338)
				)
			)
		)
	)
)
